(kicad_pcb
	(version 20260206)
	(generator "pcbnew")
	(generator_version "10.0")
	(general
		(thickness 1.6)
		(legacy_teardrops no)
	)
	(paper "A4")
	(title_block
		(title "04192023_DAF0TMB3IC0_F0TG_MB_C_brd_V02_OCP.brd")
		(comment 1 "Grand Teton / footprint 3169 of 8354 (U6016), pads 224-336 of 354")
	)
	(layers
		(0 "F.Cu" signal "TOP")
		(4 "In1.Cu" signal "GND")
		(6 "In2.Cu" signal "IN1")
		(8 "In3.Cu" signal "GND1")
		(10 "In4.Cu" signal "IN2")
		(12 "In5.Cu" signal "GND2")
		(14 "In6.Cu" signal "IN3")
		(16 "In7.Cu" signal "GND3")
		(18 "In8.Cu" signal "VCC")
		(20 "In9.Cu" signal "VCC1")
		(22 "In10.Cu" signal "GND4")
		(24 "In11.Cu" signal "IN4")
		(26 "In12.Cu" signal "GND5")
		(28 "In13.Cu" signal "IN5")
		(30 "In14.Cu" signal "GND6")
		(32 "In15.Cu" signal "IN6")
		(34 "In16.Cu" signal "GND7")
		(2 "B.Cu" signal "BOTTOM")
		(9 "F.Adhes" user "F.Adhesive")
		(11 "B.Adhes" user "B.Adhesive")
		(13 "F.Paste" user "Package Geometry/Pastemask Top")
		(15 "B.Paste" user "Package Geometry/Pastemask Bottom")
		(5 "F.SilkS" user "Ref Des/Silkscreen Top")
		(7 "B.SilkS" user "Ref Des/Silkscreen Bottom")
		(1 "F.Mask" user "Board Geometry/Soldermask Top")
		(3 "B.Mask" user "Board Geometry/Soldermask Bottom")
		(17 "Dwgs.User" user "User.Drawings")
		(19 "Cmts.User" user "User.Comments")
		(21 "Eco1.User" user "User.Eco1")
		(23 "Eco2.User" user "User.Eco2")
		(25 "Edge.Cuts" user "Board Geometry/Outline")
		(27 "Margin" user)
		(31 "F.CrtYd" user "Package Geometry/Place Bound Top")
		(29 "B.CrtYd" user "Package Geometry/Place Bound Bottom")
		(35 "F.Fab" user "Ref Des/Assembly Top")
		(33 "B.Fab" user "Ref Des/Assembly Bottom")
	)
	(footprint ""
		(layer "F.Cu")
		(at 156.0957 -387.342634)
		(property "Reference" "U6016"
			(at -8.08609 -8.07466 0)
			(unlocked yes)
			(layer "F.SilkS")
			(effects
				(font
					(size 0.7874 0.5842)
					(thickness 0.1524)
				)
				(justify left)
			)
		)
		(property "Value" ""
			(at 0 0 0)
			(layer "F.Fab")
			(effects
				(font
					(size 1.27 1.27)
				)
			)
		)
		(duplicate_pad_numbers_are_jumpers no)
		(pad "DY32" smd circle
			(at -5.997448 2.724912)
			(size 0.381 0.381)
			(layers "F.Cu" "F.Mask" "F.Paste")
			(net "GND")
		)
		(pad "E8" smd circle
			(at 10.366502 -1.988312)
			(size 0.3048 0.3048)
			(layers "F.Cu" "F.Mask" "F.Paste")
			(net "JTAG_TRST_RT_CPU1_P2_N")
		)
		(pad "E11" smd circle
			(at 10.366502 -1.388364)
			(size 0.3048 0.3048)
			(layers "F.Cu" "F.Mask" "F.Paste")
			(net "RXDET_BYP_RT_CPU1_P2")
		)
		(pad "E14" smd circle
			(at 10.366502 -0.788416)
			(size 0.3048 0.3048)
			(layers "F.Cu" "F.Mask" "F.Paste")
			(net "GND")
		)
		(pad "E18" smd circle
			(at 10.366502 -0.188468)
			(size 0.3048 0.3048)
			(layers "F.Cu" "F.Mask" "F.Paste")
			(net "Net_2224")
		)
		(pad "E27" smd circle
			(at 10.366502 1.61163)
			(size 0.3048 0.3048)
			(layers "F.Cu" "F.Mask" "F.Paste")
			(net "GND")
		)
		(pad "E30" smd circle
			(at 10.366502 2.211578)
			(size 0.3048 0.3048)
			(layers "F.Cu" "F.Mask" "F.Paste")
			(net "GND")
		)
		(pad "E33" smd circle
			(at 10.366502 2.811526)
			(size 0.3048 0.3048)
			(layers "F.Cu" "F.Mask" "F.Paste")
			(net "GND")
		)
		(pad "EA2" smd circle
			(at -6.050026 -3.41884)
			(size 0.3048 0.3048)
			(layers "F.Cu" "F.Mask" "F.Paste")
			(net "GND")
		)
		(pad "EA34" smd circle
			(at -6.050026 3.420364)
			(size 0.3048 0.3048)
			(layers "F.Cu" "F.Mask" "F.Paste")
			(net "GND")
		)
		(pad "EB1" smd oval
			(at -6.35 -3.938524)
			(size 0.254 0.3302)
			(layers "F.Cu" "F.Mask" "F.Paste")
			(net "GND")
		)
		(pad "EB35" smd oval
			(at -6.35 3.940048)
			(size 0.254 0.3302)
			(layers "F.Cu" "F.Mask" "F.Paste")
			(net "GND")
		)
		(pad "EC7" smd circle
			(at -6.397498 -2.12471)
			(size 0.381 0.381)
			(layers "F.Cu" "F.Mask" "F.Paste")
			(net "P5E_CPU1_P2_TX_BUF_DP<2>")
		)
		(pad "EC26" smd circle
			(at -6.397498 1.339342)
			(size 0.381 0.381)
			(layers "F.Cu" "F.Mask" "F.Paste")
			(net "P5E_CPU1_P2_RX_DP<2>")
		)
		(pad "ED2" smd circle
			(at -6.649974 -3.41884)
			(size 0.3048 0.3048)
			(layers "F.Cu" "F.Mask" "F.Paste")
			(net "P5E_CPU1_P2_RX_BUF_DN<2>")
		)
		(pad "ED34" smd circle
			(at -6.649974 3.420364)
			(size 0.3048 0.3048)
			(layers "F.Cu" "F.Mask" "F.Paste")
			(net "P5E_CPU1_P2_TX_C_DN<2>")
		)
		(pad "EE10" smd circle
			(at -6.797294 -1.431798)
			(size 0.381 0.381)
			(layers "F.Cu" "F.Mask" "F.Paste")
			(net "P5E_CPU1_P2_TX_BUF_DN<2>")
		)
		(pad "EE29" smd circle
			(at -6.797294 2.032254)
			(size 0.381 0.381)
			(layers "F.Cu" "F.Mask" "F.Paste")
			(net "P5E_CPU1_P2_RX_DN<2>")
		)
		(pad "EF1" smd oval
			(at -6.949948 -3.938524)
			(size 0.254 0.3302)
			(layers "F.Cu" "F.Mask" "F.Paste")
			(net "P5E_CPU1_P2_RX_BUF_DP<2>")
		)
		(pad "EF35" smd oval
			(at -6.949948 3.940048)
			(size 0.254 0.3302)
			(layers "F.Cu" "F.Mask" "F.Paste")
			(net "P5E_CPU1_P2_TX_C_DP<2>")
		)
		(pad "EG4" smd circle
			(at -7.197344 -2.817368)
			(size 0.381 0.381)
			(layers "F.Cu" "F.Mask" "F.Paste")
			(net "GND")
		)
		(pad "EG13" smd circle
			(at -7.197344 -0.79629)
			(size 0.3048 0.3048)
			(layers "F.Cu" "F.Mask" "F.Paste")
			(net "GND")
		)
		(pad "EG17" smd circle
			(at -7.197344 -0.296164)
			(size 0.3048 0.3048)
			(layers "F.Cu" "F.Mask" "F.Paste")
			(net "P0V9_CPU1_RT2_2A")
		)
		(pad "EG20" smd circle
			(at -7.197344 0.203708)
			(size 0.3048 0.3048)
			(layers "F.Cu" "F.Mask" "F.Paste")
			(net "P0V9_CPU1_RT2_2A")
		)
		(pad "EG22" smd circle
			(at -7.197344 0.703834)
			(size 0.3048 0.3048)
			(layers "F.Cu" "F.Mask" "F.Paste")
			(net "GND")
		)
		(pad "EG32" smd circle
			(at -7.197344 2.724912)
			(size 0.381 0.381)
			(layers "F.Cu" "F.Mask" "F.Paste")
			(net "GND")
		)
		(pad "EH2" smd circle
			(at -7.249922 -3.41884)
			(size 0.3048 0.3048)
			(layers "F.Cu" "F.Mask" "F.Paste")
			(net "GND")
		)
		(pad "EH34" smd circle
			(at -7.249922 3.420364)
			(size 0.3048 0.3048)
			(layers "F.Cu" "F.Mask" "F.Paste")
			(net "GND")
		)
		(pad "EJ1" smd oval
			(at -7.549896 -3.938524)
			(size 0.254 0.3302)
			(layers "F.Cu" "F.Mask" "F.Paste")
			(net "GND")
		)
		(pad "EJ35" smd oval
			(at -7.549896 3.940048)
			(size 0.254 0.3302)
			(layers "F.Cu" "F.Mask" "F.Paste")
			(net "GND")
		)
		(pad "EK7" smd circle
			(at -7.597394 -2.12471)
			(size 0.381 0.381)
			(layers "F.Cu" "F.Mask" "F.Paste")
			(net "P5E_CPU1_P2_TX_BUF_DP<1>")
		)
		(pad "EK26" smd circle
			(at -7.597394 1.339342)
			(size 0.381 0.381)
			(layers "F.Cu" "F.Mask" "F.Paste")
			(net "P5E_CPU1_P2_RX_DP<1>")
		)
		(pad "EL2" smd circle
			(at -7.850124 -3.41884)
			(size 0.3048 0.3048)
			(layers "F.Cu" "F.Mask" "F.Paste")
			(net "P5E_CPU1_P2_RX_BUF_DN<1>")
		)
		(pad "EL34" smd circle
			(at -7.850124 3.420364)
			(size 0.3048 0.3048)
			(layers "F.Cu" "F.Mask" "F.Paste")
			(net "P5E_CPU1_P2_TX_C_DP<1>")
		)
		(pad "EM10" smd circle
			(at -7.997444 -1.431798)
			(size 0.381 0.381)
			(layers "F.Cu" "F.Mask" "F.Paste")
			(net "P5E_CPU1_P2_TX_BUF_DN<1>")
		)
		(pad "EM29" smd circle
			(at -7.997444 2.032254)
			(size 0.381 0.381)
			(layers "F.Cu" "F.Mask" "F.Paste")
			(net "P5E_CPU1_P2_RX_DN<1>")
		)
		(pad "EN1" smd oval
			(at -8.150098 -3.938524)
			(size 0.254 0.3302)
			(layers "F.Cu" "F.Mask" "F.Paste")
			(net "P5E_CPU1_P2_RX_BUF_DP<1>")
		)
		(pad "EN35" smd oval
			(at -8.150098 3.940048)
			(size 0.254 0.3302)
			(layers "F.Cu" "F.Mask" "F.Paste")
			(net "P5E_CPU1_P2_TX_C_DN<1>")
		)
		(pad "EP4" smd circle
			(at -8.397494 -2.817368)
			(size 0.381 0.381)
			(layers "F.Cu" "F.Mask" "F.Paste")
			(net "GND")
		)
		(pad "EP13" smd circle
			(at -8.397494 -0.79629)
			(size 0.3048 0.3048)
			(layers "F.Cu" "F.Mask" "F.Paste")
			(net "GND")
		)
		(pad "EP17" smd circle
			(at -8.397494 -0.296164)
			(size 0.3048 0.3048)
			(layers "F.Cu" "F.Mask" "F.Paste")
			(net "P0V9_CPU1_RT2_2A")
		)
		(pad "EP20" smd circle
			(at -8.397494 0.203708)
			(size 0.3048 0.3048)
			(layers "F.Cu" "F.Mask" "F.Paste")
			(net "P0V9_CPU1_RT2_2A")
		)
		(pad "EP22" smd circle
			(at -8.397494 0.703834)
			(size 0.3048 0.3048)
			(layers "F.Cu" "F.Mask" "F.Paste")
			(net "GND")
		)
		(pad "EP32" smd circle
			(at -8.397494 2.724912)
			(size 0.381 0.381)
			(layers "F.Cu" "F.Mask" "F.Paste")
			(net "GND")
		)
		(pad "ER2" smd circle
			(at -8.450072 -3.41884)
			(size 0.3048 0.3048)
			(layers "F.Cu" "F.Mask" "F.Paste")
			(net "GND")
		)
		(pad "ER34" smd circle
			(at -8.450072 3.420364)
			(size 0.3048 0.3048)
			(layers "F.Cu" "F.Mask" "F.Paste")
			(net "GND")
		)
		(pad "ET1" smd oval
			(at -8.750046 -3.938524)
			(size 0.254 0.3302)
			(layers "F.Cu" "F.Mask" "F.Paste")
			(net "GND")
		)
		(pad "ET35" smd oval
			(at -8.750046 3.940048)
			(size 0.254 0.3302)
			(layers "F.Cu" "F.Mask" "F.Paste")
			(net "GND")
		)
		(pad "EU7" smd circle
			(at -8.79729 -2.12471)
			(size 0.381 0.381)
			(layers "F.Cu" "F.Mask" "F.Paste")
			(net "P5E_CPU1_P2_TX_BUF_DP<0>")
		)
		(pad "EU26" smd circle
			(at -8.79729 1.339342)
			(size 0.381 0.381)
			(layers "F.Cu" "F.Mask" "F.Paste")
			(net "P5E_CPU1_P2_RX_DP<0>")
		)
		(pad "EV2" smd circle
			(at -9.05002 -3.41884)
			(size 0.3048 0.3048)
			(layers "F.Cu" "F.Mask" "F.Paste")
			(net "P5E_CPU1_P2_RX_BUF_DN<0>")
		)
		(pad "EV34" smd circle
			(at -9.05002 3.420364)
			(size 0.3048 0.3048)
			(layers "F.Cu" "F.Mask" "F.Paste")
			(net "P5E_CPU1_P2_TX_C_DN<0>")
		)
		(pad "EW10" smd circle
			(at -9.19734 -1.431798)
			(size 0.381 0.381)
			(layers "F.Cu" "F.Mask" "F.Paste")
			(net "P5E_CPU1_P2_TX_BUF_DN<0>")
		)
		(pad "EW29" smd circle
			(at -9.19734 2.032254)
			(size 0.381 0.381)
			(layers "F.Cu" "F.Mask" "F.Paste")
			(net "P5E_CPU1_P2_RX_DN<0>")
		)
		(pad "EY1" smd oval
			(at -9.349994 -3.938524)
			(size 0.254 0.3302)
			(layers "F.Cu" "F.Mask" "F.Paste")
			(net "P5E_CPU1_P2_RX_BUF_DP<0>")
		)
		(pad "EY35" smd oval
			(at -9.349994 3.940048)
			(size 0.254 0.3302)
			(layers "F.Cu" "F.Mask" "F.Paste")
			(net "P5E_CPU1_P2_TX_C_DP<0>")
		)
		(pad "F2" smd circle
			(at 10.150094 -3.41884)
			(size 0.3048 0.3048)
			(layers "F.Cu" "F.Mask" "F.Paste")
			(net "RST_RT_CPU1_P2_PERST_N")
		)
		(pad "F34" smd circle
			(at 10.150094 3.420364)
			(size 0.3048 0.3048)
			(layers "F.Cu" "F.Mask" "F.Paste")
			(net "RT_CPU1_P2_ADDR1")
		)
		(pad "FA15" smd circle
			(at -9.59739 -0.738886)
			(size 0.381 0.381)
			(layers "F.Cu" "F.Mask" "F.Paste")
			(net "GND")
		)
		(pad "FA32" smd circle
			(at -9.59739 2.724912)
			(size 0.381 0.381)
			(layers "F.Cu" "F.Mask" "F.Paste")
			(net "GND")
		)
		(pad "FB2" smd circle
			(at -9.649968 -3.41884)
			(size 0.3048 0.3048)
			(layers "F.Cu" "F.Mask" "F.Paste")
			(net "GND")
		)
		(pad "FB34" smd circle
			(at -9.649968 3.420364)
			(size 0.3048 0.3048)
			(layers "F.Cu" "F.Mask" "F.Paste")
			(net "GND")
		)
		(pad "FC3" smd circle
			(at -9.846818 -2.888488)
			(size 0.3048 0.3048)
			(layers "F.Cu" "F.Mask" "F.Paste")
			(net "GND")
		)
		(pad "FC6" smd circle
			(at -9.846818 -2.288286)
			(size 0.3048 0.3048)
			(layers "F.Cu" "F.Mask" "F.Paste")
			(net "GND")
		)
		(pad "FC9" smd circle
			(at -9.846818 -1.688338)
			(size 0.3048 0.3048)
			(layers "F.Cu" "F.Mask" "F.Paste")
			(net "GND")
		)
		(pad "FC19" smd circle
			(at -9.846818 0.111506)
			(size 0.3048 0.3048)
			(layers "F.Cu" "F.Mask" "F.Paste")
			(net "GND")
		)
		(pad "FC23" smd circle
			(at -9.846818 0.711708)
			(size 0.3048 0.3048)
			(layers "F.Cu" "F.Mask" "F.Paste")
			(net "GND")
		)
		(pad "FC25" smd circle
			(at -9.846818 1.311656)
			(size 0.3048 0.3048)
			(layers "F.Cu" "F.Mask" "F.Paste")
			(net "GND")
		)
		(pad "FC28" smd circle
			(at -9.846818 1.911604)
			(size 0.3048 0.3048)
			(layers "F.Cu" "F.Mask" "F.Paste")
			(net "GND")
		)
		(pad "FD1" smd oval
			(at -9.949942 -3.938524)
			(size 0.254 0.3302)
			(layers "F.Cu" "F.Mask" "F.Paste")
			(net "GND")
		)
		(pad "FD35" smd oval
			(at -9.949942 3.940048)
			(size 0.254 0.3302)
			(layers "F.Cu" "F.Mask" "F.Paste")
			(net "GND")
		)
		(pad "FE2" smd circle
			(at -10.249916 -3.41884)
			(size 0.3048 0.3048)
			(layers "F.Cu" "F.Mask" "F.Paste")
			(net "NCF_CPU1_P2_GND")
		)
		(pad "FE34" smd circle
			(at -10.249916 3.420364)
			(size 0.3048 0.3048)
			(layers "F.Cu" "F.Mask" "F.Paste")
			(net "NCF_CPU1_P2_GND")
		)
		(pad "FF5" smd circle
			(at -10.366248 -2.588514)
			(size 0.3048 0.3048)
			(layers "F.Cu" "F.Mask" "F.Paste")
			(net "SMB_RT_CPU1_P2_ROM_MUX_1D_R_SCL")
		)
		(pad "FF8" smd circle
			(at -10.366248 -1.988312)
			(size 0.3048 0.3048)
			(layers "F.Cu" "F.Mask" "F.Paste")
			(net "JTAG_TEST_MODE_RT_CPU1_P2")
		)
		(pad "FF11" smd circle
			(at -10.366248 -1.388364)
			(size 0.3048 0.3048)
			(layers "F.Cu" "F.Mask" "F.Paste")
			(net "RST_RT_CPU1_P2_RESET_N")
		)
		(pad "FF14" smd circle
			(at -10.366248 -0.788416)
			(size 0.3048 0.3048)
			(layers "F.Cu" "F.Mask" "F.Paste")
			(net "GND")
		)
		(pad "FF18" smd circle
			(at -10.366248 -0.188468)
			(size 0.3048 0.3048)
			(layers "F.Cu" "F.Mask" "F.Paste")
			(net "CLK_100M_RETIMER_CPU1_P2_DN")
		)
		(pad "FF21" smd circle
			(at -10.366248 0.41148)
			(size 0.3048 0.3048)
			(layers "F.Cu" "F.Mask" "F.Paste")
			(net "GND")
		)
		(pad "FF24" smd circle
			(at -10.366248 1.011682)
			(size 0.3048 0.3048)
			(layers "F.Cu" "F.Mask" "F.Paste")
			(net "TEST0_RT_CPU1_P2")
		)
		(pad "FF27" smd circle
			(at -10.366248 1.61163)
			(size 0.3048 0.3048)
			(layers "F.Cu" "F.Mask" "F.Paste")
			(net "TEST1_RT_CPU1_P2")
		)
		(pad "FF30" smd circle
			(at -10.366248 2.211578)
			(size 0.3048 0.3048)
			(layers "F.Cu" "F.Mask" "F.Paste")
			(net "TEST2_RT_CPU1_P2")
		)
		(pad "FF33" smd circle
			(at -10.366248 2.811526)
			(size 0.3048 0.3048)
			(layers "F.Cu" "F.Mask" "F.Paste")
			(net "RT_CPU1_P2_SCAN_MODE")
		)
		(pad "FG1" smd oval
			(at -10.54989 -3.938524)
			(size 0.254 0.3302)
			(layers "F.Cu" "F.Mask" "F.Paste")
			(net "NCF_CPU1_P2_GND")
		)
		(pad "FG35" smd oval
			(at -10.54989 3.940048)
			(size 0.254 0.3302)
			(layers "F.Cu" "F.Mask" "F.Paste")
			(net "NCF_CPU1_P2_GND")
		)
		(pad "FH2" smd circle
			(at -10.850118 -3.41884)
			(size 0.3048 0.3048)
			(layers "F.Cu" "F.Mask" "F.Paste")
			(net "NCF_CPU1_P2_GND")
		)
		(pad "FH34" smd circle
			(at -10.850118 3.420364)
			(size 0.3048 0.3048)
			(layers "F.Cu" "F.Mask" "F.Paste")
			(net "NCF_CPU1_P2_GND")
		)
		(pad "FJ3" smd oval
			(at -10.885932 -2.888488 90)
			(size 0.254 0.3302)
			(layers "F.Cu" "F.Mask" "F.Paste")
			(net "SMB_RT_CPU1_P2_ROM_MUX_1D_R_SDA")
		)
		(pad "FJ6" smd oval
			(at -10.885932 -2.288286 90)
			(size 0.254 0.3302)
			(layers "F.Cu" "F.Mask" "F.Paste")
			(net "Net_2222")
		)
		(pad "FJ9" smd oval
			(at -10.885932 -1.688338 90)
			(size 0.254 0.3302)
			(layers "F.Cu" "F.Mask" "F.Paste")
			(net "MODE_RT_CPU1_P2")
		)
		(pad "FJ12" smd oval
			(at -10.885932 -1.08839 90)
			(size 0.254 0.3302)
			(layers "F.Cu" "F.Mask" "F.Paste")
			(net "GND")
		)
		(pad "FJ16" smd oval
			(at -10.885932 -0.488442 90)
			(size 0.254 0.3302)
			(layers "F.Cu" "F.Mask" "F.Paste")
			(net "CLK_100M_RETIMER_CPU1_P2_DP")
		)
		(pad "FJ19" smd oval
			(at -10.885932 0.111506 90)
			(size 0.254 0.3302)
			(layers "F.Cu" "F.Mask" "F.Paste")
			(net "GND")
		)
		(pad "FJ23" smd oval
			(at -10.885932 0.711708 90)
			(size 0.254 0.3302)
			(layers "F.Cu" "F.Mask" "F.Paste")
			(net "Net_2223")
		)
		(pad "FJ25" smd oval
			(at -10.885932 1.311656 90)
			(size 0.254 0.3302)
			(layers "F.Cu" "F.Mask" "F.Paste")
			(net "GPIO2_RT_CPU1_P2")
		)
		(pad "FJ28" smd oval
			(at -10.885932 1.911604 90)
			(size 0.254 0.3302)
			(layers "F.Cu" "F.Mask" "F.Paste")
			(net "GPIO3_RT_CPU1_P2")
		)
		(pad "FJ31" smd oval
			(at -10.885932 2.511552 90)
			(size 0.254 0.3302)
			(layers "F.Cu" "F.Mask" "F.Paste")
			(net "Net_56")
		)
		(pad "G1" smd oval
			(at 9.85012 -3.938524)
			(size 0.254 0.3302)
			(layers "F.Cu" "F.Mask" "F.Paste")
			(net "RT_CPU1_P2_VQPS")
		)
		(pad "G35" smd oval
			(at 9.85012 3.940048)
			(size 0.254 0.3302)
			(layers "F.Cu" "F.Mask" "F.Paste")
			(net "CLKREQ_RT_CPU1_P2_N")
		)
		(pad "H12" smd circle
			(at 9.846818 -1.08839)
			(size 0.3048 0.3048)
			(layers "F.Cu" "F.Mask" "F.Paste")
			(net "GND")
		)
		(pad "H16" smd circle
			(at 9.846818 -0.488442)
			(size 0.3048 0.3048)
			(layers "F.Cu" "F.Mask" "F.Paste")
			(net "GND")
		)
		(pad "H19" smd circle
			(at 9.846818 0.111506)
			(size 0.3048 0.3048)
			(layers "F.Cu" "F.Mask" "F.Paste")
			(net "GND")
		)
		(pad "H31" smd circle
			(at 9.846818 2.511552)
			(size 0.3048 0.3048)
			(layers "F.Cu" "F.Mask" "F.Paste")
			(net "GND")
		)
		(pad "J4" smd circle
			(at 9.602724 -2.817368)
			(size 0.381 0.381)
			(layers "F.Cu" "F.Mask" "F.Paste")
			(net "GND")
		)
		(pad "J22" smd circle
			(at 9.602724 0.703834)
			(size 0.3048 0.3048)
			(layers "F.Cu" "F.Mask" "F.Paste")
			(net "GND")
		)
		(pad "K2" smd circle
			(at 9.549892 -3.41884)
			(size 0.3048 0.3048)
			(layers "F.Cu" "F.Mask" "F.Paste")
			(net "GND")
		)
		(pad "K34" smd circle
			(at 9.549892 3.420364)
			(size 0.3048 0.3048)
			(layers "F.Cu" "F.Mask" "F.Paste")
			(net "GND")
		)
		(pad "L1" smd oval
			(at 9.249918 -3.938524)
			(size 0.254 0.3302)
			(layers "F.Cu" "F.Mask" "F.Paste")
			(net "GND")
		)
		(pad "L35" smd oval
			(at 9.249918 3.940048)
			(size 0.254 0.3302)
			(layers "F.Cu" "F.Mask" "F.Paste")
			(net "GND")
		)
		(pad "M7" smd circle
			(at 9.202674 -2.12471)
			(size 0.381 0.381)
			(layers "F.Cu" "F.Mask" "F.Paste")
			(net "P5E_CPU1_P2_TX_BUF_DP<15>")
		)
		(pad "M26" smd circle
			(at 9.202674 1.339342)
			(size 0.381 0.381)
			(layers "F.Cu" "F.Mask" "F.Paste")
			(net "P5E_CPU1_P2_RX_DP<15>")
		)
		(pad "N2" smd circle
			(at 8.949944 -3.41884)
			(size 0.3048 0.3048)
			(layers "F.Cu" "F.Mask" "F.Paste")
			(net "P5E_CPU1_P2_RX_BUF_DN<15>")
		)
		(pad "N34" smd circle
			(at 8.949944 3.420364)
			(size 0.3048 0.3048)
			(layers "F.Cu" "F.Mask" "F.Paste")
			(net "P5E_CPU1_P2_TX_C_DN<15>")
		)
	)
)
